(kicad_pcb
	(version 20260206)
	(generator "pcbnew")
	(generator_version "10.0")
	(general
		(thickness 1.6)
		(legacy_teardrops no)
	)
	(paper "A4")
	(title_block
		(title "03242023_DA0F0TMBIJ0_F0T_Motherboard_J_brd_V01_OCP.brd")
		(comment 1 "Grand Teton / footprints 5974-5979 of 6105")
	)
	(layers
		(0 "F.Cu" signal "TOP")
		(4 "In1.Cu" signal "GND")
		(6 "In2.Cu" signal "IN1")
		(8 "In3.Cu" signal "GND1")
		(10 "In4.Cu" signal "IN2")
		(12 "In5.Cu" signal "GND2")
		(14 "In6.Cu" signal "IN3")
		(16 "In7.Cu" signal "GND3")
		(18 "In8.Cu" signal "VCC")
		(20 "In9.Cu" signal "VCC1")
		(22 "In10.Cu" signal "GND4")
		(24 "In11.Cu" signal "IN4")
		(26 "In12.Cu" signal "GND5")
		(28 "In13.Cu" signal "IN5")
		(30 "In14.Cu" signal "GND6")
		(32 "In15.Cu" signal "IN6")
		(34 "In16.Cu" signal "GND7")
		(2 "B.Cu" signal "BOTTOM")
		(9 "F.Adhes" user "F.Adhesive")
		(11 "B.Adhes" user "B.Adhesive")
		(13 "F.Paste" user "Package Geometry/Pastemask Top")
		(15 "B.Paste" user "Package Geometry/Pastemask Bottom")
		(5 "F.SilkS" user "Ref Des/Silkscreen Top")
		(7 "B.SilkS" user "Ref Des/Silkscreen Bottom")
		(1 "F.Mask" user "Board Geometry/Soldermask Top")
		(3 "B.Mask" user "Board Geometry/Soldermask Bottom")
		(17 "Dwgs.User" user "User.Drawings")
		(19 "Cmts.User" user "User.Comments")
		(21 "Eco1.User" user "User.Eco1")
		(23 "Eco2.User" user "User.Eco2")
		(25 "Edge.Cuts" user "Board Geometry/Outline")
		(27 "Margin" user)
		(31 "F.CrtYd" user "Package Geometry/Place Bound Top")
		(29 "B.CrtYd" user "Package Geometry/Place Bound Bottom")
		(35 "F.Fab" user "Ref Des/Assembly Top")
		(33 "B.Fab" user "Ref Des/Assembly Bottom")
	)
	(footprint ""
		(layer "B.Cu")
		(at 64.990218 -318.962024 180)
		(property "Reference" "R944"
			(at 0 0 0)
			(layer "B.SilkS")
			(hide yes)
			(effects
				(font
					(size 1.27 1.27)
				)
				(justify mirror)
			)
		)
		(property "Value" ""
			(at 0 0 0)
			(layer "B.Fab")
			(effects
				(font
					(size 1.27 1.27)
				)
				(justify mirror)
			)
		)
		(duplicate_pad_numbers_are_jumpers no)
		(fp_line
			(start 0.7874 0.4064)
			(end 0.7874 -0.4064)
			(stroke
				(width 0.1524)
				(type default)
			)
			(layer "B.SilkS")
		)
		(fp_line
			(start 0.7874 -0.4064)
			(end -0.7874 -0.4064)
			(stroke
				(width 0.1524)
				(type default)
			)
			(layer "B.SilkS")
		)
		(fp_line
			(start -0.7874 0.4064)
			(end 0.7874 0.4064)
			(stroke
				(width 0.1524)
				(type default)
			)
			(layer "B.SilkS")
		)
		(fp_line
			(start -0.7874 -0.4064)
			(end -0.7874 0.4064)
			(stroke
				(width 0.1524)
				(type default)
			)
			(layer "B.SilkS")
		)
		(fp_line
			(start 0.67945 0.3048)
			(end 0.67945 -0.305054)
			(stroke
				(width 0.1)
				(type default)
			)
			(layer "B.Fab")
		)
		(fp_line
			(start 0.67945 -0.305054)
			(end 0.12065 -0.305054)
			(stroke
				(width 0.1)
				(type default)
			)
			(layer "B.Fab")
		)
		(fp_line
			(start 0.12065 0.3048)
			(end 0.67945 0.3048)
			(stroke
				(width 0.1)
				(type default)
			)
			(layer "B.Fab")
		)
		(fp_line
			(start 0.12065 0.2794)
			(end 0.12065 0.3048)
			(stroke
				(width 0.1)
				(type default)
			)
			(layer "B.Fab")
		)
		(fp_line
			(start 0.12065 -0.2794)
			(end -0.12065 -0.2794)
			(stroke
				(width 0.1)
				(type default)
			)
			(layer "B.Fab")
		)
		(fp_line
			(start 0.12065 -0.305054)
			(end 0.12065 -0.2794)
			(stroke
				(width 0.1)
				(type default)
			)
			(layer "B.Fab")
		)
		(fp_line
			(start -0.120396 0.3048)
			(end -0.120396 0.2794)
			(stroke
				(width 0.1)
				(type default)
			)
			(layer "B.Fab")
		)
		(fp_line
			(start -0.120396 0.2794)
			(end 0.12065 0.2794)
			(stroke
				(width 0.1)
				(type default)
			)
			(layer "B.Fab")
		)
		(fp_line
			(start -0.12065 -0.2794)
			(end -0.12065 -0.3048)
			(stroke
				(width 0.1)
				(type default)
			)
			(layer "B.Fab")
		)
		(fp_line
			(start -0.12065 -0.3048)
			(end -0.67945 -0.3048)
			(stroke
				(width 0.1)
				(type default)
			)
			(layer "B.Fab")
		)
		(fp_line
			(start -0.67945 0.3048)
			(end -0.120396 0.3048)
			(stroke
				(width 0.1)
				(type default)
			)
			(layer "B.Fab")
		)
		(fp_line
			(start -0.67945 -0.3048)
			(end -0.67945 0.3048)
			(stroke
				(width 0.1)
				(type default)
			)
			(layer "B.Fab")
		)
		(pad "1" smd circle
			(at 0.40005 0)
			(size 0 0)
			(layers "B.Cu" "B.Mask" "B.Paste")
			(net "P3V3_AUX")
		)
		(pad "2" smd circle
			(at -0.40005 0)
			(size 0 0)
			(layers "B.Cu" "B.Mask" "B.Paste")
			(net "PWRGD_FAIL_CPU1_AB_R1")
		)
	)
	(footprint ""
		(layer "B.Cu")
		(at 39.621206 -318.366648)
		(property "Reference" "R44"
			(at 0 0 0)
			(layer "B.SilkS")
			(hide yes)
			(effects
				(font
					(size 1.27 1.27)
				)
				(justify mirror)
			)
		)
		(property "Value" ""
			(at 0 0 0)
			(layer "B.Fab")
			(effects
				(font
					(size 1.27 1.27)
				)
				(justify mirror)
			)
		)
		(duplicate_pad_numbers_are_jumpers no)
		(fp_line
			(start -0.7874 -0.4064)
			(end -0.7874 0.4064)
			(stroke
				(width 0.1524)
				(type default)
			)
			(layer "B.SilkS")
		)
		(fp_line
			(start -0.7874 0.4064)
			(end 0.7874 0.4064)
			(stroke
				(width 0.1524)
				(type default)
			)
			(layer "B.SilkS")
		)
		(fp_line
			(start 0.7874 -0.4064)
			(end -0.7874 -0.4064)
			(stroke
				(width 0.1524)
				(type default)
			)
			(layer "B.SilkS")
		)
		(fp_line
			(start 0.7874 0.4064)
			(end 0.7874 -0.4064)
			(stroke
				(width 0.1524)
				(type default)
			)
			(layer "B.SilkS")
		)
		(fp_line
			(start -0.67945 -0.3048)
			(end -0.67945 0.3048)
			(stroke
				(width 0.1)
				(type default)
			)
			(layer "B.Fab")
		)
		(fp_line
			(start -0.67945 0.3048)
			(end -0.120396 0.3048)
			(stroke
				(width 0.1)
				(type default)
			)
			(layer "B.Fab")
		)
		(fp_line
			(start -0.12065 -0.3048)
			(end -0.67945 -0.3048)
			(stroke
				(width 0.1)
				(type default)
			)
			(layer "B.Fab")
		)
		(fp_line
			(start -0.12065 -0.2794)
			(end -0.12065 -0.3048)
			(stroke
				(width 0.1)
				(type default)
			)
			(layer "B.Fab")
		)
		(fp_line
			(start -0.120396 0.2794)
			(end 0.12065 0.2794)
			(stroke
				(width 0.1)
				(type default)
			)
			(layer "B.Fab")
		)
		(fp_line
			(start -0.120396 0.3048)
			(end -0.120396 0.2794)
			(stroke
				(width 0.1)
				(type default)
			)
			(layer "B.Fab")
		)
		(fp_line
			(start 0.12065 -0.305054)
			(end 0.12065 -0.2794)
			(stroke
				(width 0.1)
				(type default)
			)
			(layer "B.Fab")
		)
		(fp_line
			(start 0.12065 -0.2794)
			(end -0.12065 -0.2794)
			(stroke
				(width 0.1)
				(type default)
			)
			(layer "B.Fab")
		)
		(fp_line
			(start 0.12065 0.2794)
			(end 0.12065 0.3048)
			(stroke
				(width 0.1)
				(type default)
			)
			(layer "B.Fab")
		)
		(fp_line
			(start 0.12065 0.3048)
			(end 0.67945 0.3048)
			(stroke
				(width 0.1)
				(type default)
			)
			(layer "B.Fab")
		)
		(fp_line
			(start 0.67945 -0.305054)
			(end 0.12065 -0.305054)
			(stroke
				(width 0.1)
				(type default)
			)
			(layer "B.Fab")
		)
		(fp_line
			(start 0.67945 0.3048)
			(end 0.67945 -0.305054)
			(stroke
				(width 0.1)
				(type default)
			)
			(layer "B.Fab")
		)
		(pad "1" smd circle
			(at 0.40005 0 180)
			(size 0 0)
			(layers "B.Cu" "B.Mask" "B.Paste")
			(net "PD_CHB_CPU1_DIMM1_SAA")
		)
		(pad "2" smd circle
			(at -0.40005 0 180)
			(size 0 0)
			(layers "B.Cu" "B.Mask" "B.Paste")
			(net "GND")
		)
	)
	(footprint ""
		(layer "B.Cu")
		(at 97.257108 -190.705232 -90)
		(property "Reference" "R64"
			(at 0 0 90)
			(layer "B.SilkS")
			(hide yes)
			(effects
				(font
					(size 1.27 1.27)
				)
				(justify mirror)
			)
		)
		(property "Value" ""
			(at 0 0 90)
			(layer "B.Fab")
			(effects
				(font
					(size 1.27 1.27)
				)
				(justify mirror)
			)
		)
		(duplicate_pad_numbers_are_jumpers no)
		(fp_line
			(start -0.7874 0.4064)
			(end 0.7874 0.4064)
			(stroke
				(width 0.1524)
				(type default)
			)
			(layer "B.SilkS")
		)
		(fp_line
			(start 0.7874 0.4064)
			(end 0.7874 -0.4064)
			(stroke
				(width 0.1524)
				(type default)
			)
			(layer "B.SilkS")
		)
		(fp_line
			(start -0.7874 -0.4064)
			(end -0.7874 0.4064)
			(stroke
				(width 0.1524)
				(type default)
			)
			(layer "B.SilkS")
		)
		(fp_line
			(start 0.7874 -0.4064)
			(end -0.7874 -0.4064)
			(stroke
				(width 0.1524)
				(type default)
			)
			(layer "B.SilkS")
		)
		(fp_line
			(start -0.67945 0.3048)
			(end -0.120396 0.3048)
			(stroke
				(width 0.1)
				(type default)
			)
			(layer "B.Fab")
		)
		(fp_line
			(start -0.120396 0.3048)
			(end -0.120396 0.2794)
			(stroke
				(width 0.1)
				(type default)
			)
			(layer "B.Fab")
		)
		(fp_line
			(start 0.12065 0.3048)
			(end 0.67945 0.3048)
			(stroke
				(width 0.1)
				(type default)
			)
			(layer "B.Fab")
		)
		(fp_line
			(start 0.67945 0.3048)
			(end 0.67945 -0.305054)
			(stroke
				(width 0.1)
				(type default)
			)
			(layer "B.Fab")
		)
		(fp_line
			(start -0.120396 0.2794)
			(end 0.12065 0.2794)
			(stroke
				(width 0.1)
				(type default)
			)
			(layer "B.Fab")
		)
		(fp_line
			(start 0.12065 0.2794)
			(end 0.12065 0.3048)
			(stroke
				(width 0.1)
				(type default)
			)
			(layer "B.Fab")
		)
		(fp_line
			(start -0.12065 -0.2794)
			(end -0.12065 -0.3048)
			(stroke
				(width 0.1)
				(type default)
			)
			(layer "B.Fab")
		)
		(fp_line
			(start 0.12065 -0.2794)
			(end -0.12065 -0.2794)
			(stroke
				(width 0.1)
				(type default)
			)
			(layer "B.Fab")
		)
		(fp_line
			(start -0.67945 -0.3048)
			(end -0.67945 0.3048)
			(stroke
				(width 0.1)
				(type default)
			)
			(layer "B.Fab")
		)
		(fp_line
			(start -0.12065 -0.3048)
			(end -0.67945 -0.3048)
			(stroke
				(width 0.1)
				(type default)
			)
			(layer "B.Fab")
		)
		(fp_line
			(start 0.12065 -0.305054)
			(end 0.12065 -0.2794)
			(stroke
				(width 0.1)
				(type default)
			)
			(layer "B.Fab")
		)
		(fp_line
			(start 0.67945 -0.305054)
			(end 0.12065 -0.305054)
			(stroke
				(width 0.1)
				(type default)
			)
			(layer "B.Fab")
		)
		(pad "1" smd circle
			(at 0.40005 0 90)
			(size 0 0)
			(layers "B.Cu" "B.Mask" "B.Paste")
			(net "JTAG_MUX_CPU1_GTL_TDI")
		)
		(pad "2" smd circle
			(at -0.40005 0 90)
			(size 0 0)
			(layers "B.Cu" "B.Mask" "B.Paste")
			(net "JTAG_DBP_CPU1_GTL_R_TDI")
		)
	)
	(footprint ""
		(layer "B.Cu")
		(at 181.915308 -407.859484 -90)
		(property "Reference" "R4695"
			(at 0 0 90)
			(layer "B.SilkS")
			(hide yes)
			(effects
				(font
					(size 1.27 1.27)
				)
				(justify mirror)
			)
		)
		(property "Value" ""
			(at 0 0 90)
			(layer "B.Fab")
			(effects
				(font
					(size 1.27 1.27)
				)
				(justify mirror)
			)
		)
		(duplicate_pad_numbers_are_jumpers no)
		(fp_line
			(start -0.7874 0.4064)
			(end 0.7874 0.4064)
			(stroke
				(width 0.1524)
				(type default)
			)
			(layer "B.SilkS")
		)
		(fp_line
			(start 0.7874 0.4064)
			(end 0.7874 -0.4064)
			(stroke
				(width 0.1524)
				(type default)
			)
			(layer "B.SilkS")
		)
		(fp_line
			(start -0.7874 -0.4064)
			(end -0.7874 0.4064)
			(stroke
				(width 0.1524)
				(type default)
			)
			(layer "B.SilkS")
		)
		(fp_line
			(start 0.7874 -0.4064)
			(end -0.7874 -0.4064)
			(stroke
				(width 0.1524)
				(type default)
			)
			(layer "B.SilkS")
		)
		(fp_line
			(start -0.67945 0.3048)
			(end -0.120396 0.3048)
			(stroke
				(width 0.1)
				(type default)
			)
			(layer "B.Fab")
		)
		(fp_line
			(start -0.120396 0.3048)
			(end -0.120396 0.2794)
			(stroke
				(width 0.1)
				(type default)
			)
			(layer "B.Fab")
		)
		(fp_line
			(start 0.12065 0.3048)
			(end 0.67945 0.3048)
			(stroke
				(width 0.1)
				(type default)
			)
			(layer "B.Fab")
		)
		(fp_line
			(start 0.67945 0.3048)
			(end 0.67945 -0.305054)
			(stroke
				(width 0.1)
				(type default)
			)
			(layer "B.Fab")
		)
		(fp_line
			(start -0.120396 0.2794)
			(end 0.12065 0.2794)
			(stroke
				(width 0.1)
				(type default)
			)
			(layer "B.Fab")
		)
		(fp_line
			(start 0.12065 0.2794)
			(end 0.12065 0.3048)
			(stroke
				(width 0.1)
				(type default)
			)
			(layer "B.Fab")
		)
		(fp_line
			(start -0.12065 -0.2794)
			(end -0.12065 -0.3048)
			(stroke
				(width 0.1)
				(type default)
			)
			(layer "B.Fab")
		)
		(fp_line
			(start 0.12065 -0.2794)
			(end -0.12065 -0.2794)
			(stroke
				(width 0.1)
				(type default)
			)
			(layer "B.Fab")
		)
		(fp_line
			(start -0.67945 -0.3048)
			(end -0.67945 0.3048)
			(stroke
				(width 0.1)
				(type default)
			)
			(layer "B.Fab")
		)
		(fp_line
			(start -0.12065 -0.3048)
			(end -0.67945 -0.3048)
			(stroke
				(width 0.1)
				(type default)
			)
			(layer "B.Fab")
		)
		(fp_line
			(start 0.12065 -0.305054)
			(end 0.12065 -0.2794)
			(stroke
				(width 0.1)
				(type default)
			)
			(layer "B.Fab")
		)
		(fp_line
			(start 0.67945 -0.305054)
			(end 0.12065 -0.305054)
			(stroke
				(width 0.1)
				(type default)
			)
			(layer "B.Fab")
		)
		(pad "1" smd circle
			(at 0.40005 0 90)
			(size 0 0)
			(layers "B.Cu" "B.Mask" "B.Paste")
			(net "SMB_SML1_PMBUS_HSC_SCL")
		)
		(pad "2" smd circle
			(at -0.40005 0 90)
			(size 0 0)
			(layers "B.Cu" "B.Mask" "B.Paste")
			(net "SMB_SML1_PMBUS_HSC_MODULE_SCL")
		)
	)
	(footprint ""
		(layer "B.Cu")
		(at 401.832318 -227.224082 90)
		(property "Reference" "R2362"
			(at 0 0 90)
			(layer "B.SilkS")
			(hide yes)
			(effects
				(font
					(size 1.27 1.27)
				)
				(justify mirror)
			)
		)
		(property "Value" ""
			(at 0 0 90)
			(layer "B.Fab")
			(effects
				(font
					(size 1.27 1.27)
				)
				(justify mirror)
			)
		)
		(duplicate_pad_numbers_are_jumpers no)
		(fp_line
			(start 0.7874 -0.4064)
			(end -0.7874 -0.4064)
			(stroke
				(width 0.1524)
				(type default)
			)
			(layer "B.SilkS")
		)
		(fp_line
			(start -0.7874 -0.4064)
			(end -0.7874 0.4064)
			(stroke
				(width 0.1524)
				(type default)
			)
			(layer "B.SilkS")
		)
		(fp_line
			(start 0.7874 0.4064)
			(end 0.7874 -0.4064)
			(stroke
				(width 0.1524)
				(type default)
			)
			(layer "B.SilkS")
		)
		(fp_line
			(start -0.7874 0.4064)
			(end 0.7874 0.4064)
			(stroke
				(width 0.1524)
				(type default)
			)
			(layer "B.SilkS")
		)
		(fp_line
			(start 0.67945 -0.305054)
			(end 0.12065 -0.305054)
			(stroke
				(width 0.1)
				(type default)
			)
			(layer "B.Fab")
		)
		(fp_line
			(start 0.12065 -0.305054)
			(end 0.12065 -0.2794)
			(stroke
				(width 0.1)
				(type default)
			)
			(layer "B.Fab")
		)
		(fp_line
			(start -0.12065 -0.3048)
			(end -0.67945 -0.3048)
			(stroke
				(width 0.1)
				(type default)
			)
			(layer "B.Fab")
		)
		(fp_line
			(start -0.67945 -0.3048)
			(end -0.67945 0.3048)
			(stroke
				(width 0.1)
				(type default)
			)
			(layer "B.Fab")
		)
		(fp_line
			(start 0.12065 -0.2794)
			(end -0.12065 -0.2794)
			(stroke
				(width 0.1)
				(type default)
			)
			(layer "B.Fab")
		)
		(fp_line
			(start -0.12065 -0.2794)
			(end -0.12065 -0.3048)
			(stroke
				(width 0.1)
				(type default)
			)
			(layer "B.Fab")
		)
		(fp_line
			(start 0.12065 0.2794)
			(end 0.12065 0.3048)
			(stroke
				(width 0.1)
				(type default)
			)
			(layer "B.Fab")
		)
		(fp_line
			(start -0.120396 0.2794)
			(end 0.12065 0.2794)
			(stroke
				(width 0.1)
				(type default)
			)
			(layer "B.Fab")
		)
		(fp_line
			(start 0.67945 0.3048)
			(end 0.67945 -0.305054)
			(stroke
				(width 0.1)
				(type default)
			)
			(layer "B.Fab")
		)
		(fp_line
			(start 0.12065 0.3048)
			(end 0.67945 0.3048)
			(stroke
				(width 0.1)
				(type default)
			)
			(layer "B.Fab")
		)
		(fp_line
			(start -0.120396 0.3048)
			(end -0.120396 0.2794)
			(stroke
				(width 0.1)
				(type default)
			)
			(layer "B.Fab")
		)
		(fp_line
			(start -0.67945 0.3048)
			(end -0.120396 0.3048)
			(stroke
				(width 0.1)
				(type default)
			)
			(layer "B.Fab")
		)
		(pad "1" smd circle
			(at 0.40005 0 270)
			(size 0 0)
			(layers "B.Cu" "B.Mask" "B.Paste")
			(net "H_CPU0_PMDOWN_CPU1_R")
		)
		(pad "2" smd circle
			(at -0.40005 0 270)
			(size 0 0)
			(layers "B.Cu" "B.Mask" "B.Paste")
			(net "H_CPU0_PMDOWN_CPU1_R1")
		)
	)
	(footprint ""
		(layer "B.Cu")
		(at 451.947026 -77.51572 90)
		(property "Reference" "R1571"
			(at 0 0 90)
			(layer "B.SilkS")
			(hide yes)
			(effects
				(font
					(size 1.27 1.27)
				)
				(justify mirror)
			)
		)
		(property "Value" ""
			(at 0 0 90)
			(layer "B.Fab")
			(effects
				(font
					(size 1.27 1.27)
				)
				(justify mirror)
			)
		)
		(duplicate_pad_numbers_are_jumpers no)
		(fp_line
			(start 0.7874 -0.4064)
			(end -0.7874 -0.4064)
			(stroke
				(width 0.1524)
				(type default)
			)
			(layer "B.SilkS")
		)
		(fp_line
			(start -0.7874 -0.4064)
			(end -0.7874 0.4064)
			(stroke
				(width 0.1524)
				(type default)
			)
			(layer "B.SilkS")
		)
		(fp_line
			(start 0.7874 0.4064)
			(end 0.7874 -0.4064)
			(stroke
				(width 0.1524)
				(type default)
			)
			(layer "B.SilkS")
		)
		(fp_line
			(start -0.7874 0.4064)
			(end 0.7874 0.4064)
			(stroke
				(width 0.1524)
				(type default)
			)
			(layer "B.SilkS")
		)
		(fp_line
			(start 0.67945 -0.305054)
			(end 0.12065 -0.305054)
			(stroke
				(width 0.1)
				(type default)
			)
			(layer "B.Fab")
		)
		(fp_line
			(start 0.12065 -0.305054)
			(end 0.12065 -0.2794)
			(stroke
				(width 0.1)
				(type default)
			)
			(layer "B.Fab")
		)
		(fp_line
			(start -0.12065 -0.3048)
			(end -0.67945 -0.3048)
			(stroke
				(width 0.1)
				(type default)
			)
			(layer "B.Fab")
		)
		(fp_line
			(start -0.67945 -0.3048)
			(end -0.67945 0.3048)
			(stroke
				(width 0.1)
				(type default)
			)
			(layer "B.Fab")
		)
		(fp_line
			(start 0.12065 -0.2794)
			(end -0.12065 -0.2794)
			(stroke
				(width 0.1)
				(type default)
			)
			(layer "B.Fab")
		)
		(fp_line
			(start -0.12065 -0.2794)
			(end -0.12065 -0.3048)
			(stroke
				(width 0.1)
				(type default)
			)
			(layer "B.Fab")
		)
		(fp_line
			(start 0.12065 0.2794)
			(end 0.12065 0.3048)
			(stroke
				(width 0.1)
				(type default)
			)
			(layer "B.Fab")
		)
		(fp_line
			(start -0.120396 0.2794)
			(end 0.12065 0.2794)
			(stroke
				(width 0.1)
				(type default)
			)
			(layer "B.Fab")
		)
		(fp_line
			(start 0.67945 0.3048)
			(end 0.67945 -0.305054)
			(stroke
				(width 0.1)
				(type default)
			)
			(layer "B.Fab")
		)
		(fp_line
			(start 0.12065 0.3048)
			(end 0.67945 0.3048)
			(stroke
				(width 0.1)
				(type default)
			)
			(layer "B.Fab")
		)
		(fp_line
			(start -0.120396 0.3048)
			(end -0.120396 0.2794)
			(stroke
				(width 0.1)
				(type default)
			)
			(layer "B.Fab")
		)
		(fp_line
			(start -0.67945 0.3048)
			(end -0.120396 0.3048)
			(stroke
				(width 0.1)
				(type default)
			)
			(layer "B.Fab")
		)
		(pad "1" smd circle
			(at 0.40005 0 270)
			(size 0 0)
			(layers "B.Cu" "B.Mask" "B.Paste")
			(net "MB0_P12V_STBY_PWRGD")
		)
		(pad "2" smd circle
			(at -0.40005 0 270)
			(size 0 0)
			(layers "B.Cu" "B.Mask" "B.Paste")
			(net "P3V3_AUX_EN")
		)
	)
)
